(kicad_pcb
	(version 20260206)
	(generator "pcbnew")
	(generator_version "10.0")
	(general
		(thickness 1.6)
		(legacy_teardrops no)
	)
	(paper "A4")
	(title_block
		(title "Wiwynn_Tioga_Pass_MB.brd")
		(comment 1 "Tioga Pass / footprints 2050-2056 of 4770")
	)
	(layers
		(0 "F.Cu" signal "TOP")
		(4 "In1.Cu" signal "L2GND")
		(6 "In2.Cu" signal "L3")
		(8 "In3.Cu" signal "L4GND")
		(10 "In4.Cu" signal "L5")
		(12 "In5.Cu" signal "L6GND")
		(14 "In6.Cu" signal "L7VCC")
		(16 "In7.Cu" signal "L8VCC")
		(18 "In8.Cu" signal "L9GND")
		(20 "In9.Cu" signal "L10")
		(22 "In10.Cu" signal "L11GND")
		(24 "In11.Cu" signal "L12")
		(26 "In12.Cu" signal "L13GND")
		(2 "B.Cu" signal "BOTTOM")
		(9 "F.Adhes" user "F.Adhesive")
		(11 "B.Adhes" user "B.Adhesive")
		(13 "F.Paste" user "Package Geometry/Pastemask Top")
		(15 "B.Paste" user "Package Geometry/Pastemask Bottom")
		(5 "F.SilkS" user "Ref Des/Silkscreen Top")
		(7 "B.SilkS" user "Ref Des/Silkscreen Bottom")
		(1 "F.Mask" user "Board Geometry/Soldermask Top")
		(3 "B.Mask" user "Board Geometry/Soldermask Bottom")
		(17 "Dwgs.User" user "User.Drawings")
		(19 "Cmts.User" user "User.Comments")
		(21 "Eco1.User" user "User.Eco1")
		(23 "Eco2.User" user "User.Eco2")
		(25 "Edge.Cuts" user "Board Geometry/Outline")
		(27 "Margin" user)
		(31 "F.CrtYd" user "Package Geometry/Place Bound Top")
		(29 "B.CrtYd" user "Package Geometry/Place Bound Bottom")
		(35 "F.Fab" user "Ref Des/Assembly Top")
		(33 "B.Fab" user "Ref Des/Assembly Bottom")
	)
	(footprint ""
		(layer "F.Cu")
		(at 24.257 -32.385)
		(property "Reference" "CR1F1"
			(at 1.651 -1.11633 0)
			(unlocked yes)
			(layer "F.SilkS")
			(effects
				(font
					(size 0.7874 0.5842)
					(thickness 0.1524)
				)
				(justify left)
			)
		)
		(property "Value" ""
			(at 0 0 0)
			(layer "F.Fab")
			(effects
				(font
					(size 1.27 1.27)
				)
			)
		)
		(duplicate_pad_numbers_are_jumpers no)
		(fp_line
			(start -1.8161 1.664462)
			(end -1.335278 0.831596)
			(stroke
				(width 0.1524)
				(type default)
			)
			(layer "F.SilkS")
		)
		(fp_line
			(start -1.335278 -0.291846)
			(end -1.335278 0.831596)
			(stroke
				(width 0.1524)
				(type default)
			)
			(layer "F.SilkS")
		)
		(fp_line
			(start -1.335278 0.831596)
			(end -0.854456 1.664462)
			(stroke
				(width 0.1524)
				(type default)
			)
			(layer "F.SilkS")
		)
		(fp_line
			(start -1.335278 1.664462)
			(end -1.8161 1.664462)
			(stroke
				(width 0.1524)
				(type default)
			)
			(layer "F.SilkS")
		)
		(fp_line
			(start -1.335278 2.576068)
			(end -1.335278 1.664462)
			(stroke
				(width 0.1524)
				(type default)
			)
			(layer "F.SilkS")
		)
		(fp_line
			(start -0.854456 0.831596)
			(end -1.8161 0.831596)
			(stroke
				(width 0.1524)
				(type default)
			)
			(layer "F.SilkS")
		)
		(fp_line
			(start -0.854456 1.664462)
			(end -1.335278 1.664462)
			(stroke
				(width 0.1524)
				(type default)
			)
			(layer "F.SilkS")
		)
		(fp_rect
			(start -0.67437 2.04216)
			(end 0.67437 0.24384)
			(stroke
				(width 0)
				(type default)
			)
			(fill no)
			(layer "F.CrtYd")
		)
		(fp_line
			(start -1.8161 1.664462)
			(end -1.335278 0.831596)
			(stroke
				(width 0.1)
				(type default)
			)
			(layer "F.Fab")
		)
		(fp_line
			(start -1.335278 0.831596)
			(end -1.335278 -0.291846)
			(stroke
				(width 0.1)
				(type default)
			)
			(layer "F.Fab")
		)
		(fp_line
			(start -1.335278 0.831596)
			(end -0.854456 1.664462)
			(stroke
				(width 0.1)
				(type default)
			)
			(layer "F.Fab")
		)
		(fp_line
			(start -1.335278 1.664462)
			(end -1.335278 2.576068)
			(stroke
				(width 0.1)
				(type default)
			)
			(layer "F.Fab")
		)
		(fp_line
			(start -0.854456 0.831596)
			(end -1.8161 0.831596)
			(stroke
				(width 0.1)
				(type default)
			)
			(layer "F.Fab")
		)
		(fp_line
			(start -0.854456 1.664462)
			(end -1.8161 1.664462)
			(stroke
				(width 0.1)
				(type default)
			)
			(layer "F.Fab")
		)
		(fp_line
			(start -0.67437 0.24384)
			(end -0.67437 2.04216)
			(stroke
				(width 0.1)
				(type default)
			)
			(layer "F.Fab")
		)
		(fp_line
			(start -0.67437 2.04216)
			(end 0.67437 2.04216)
			(stroke
				(width 0.1)
				(type default)
			)
			(layer "F.Fab")
		)
		(fp_line
			(start 0.67437 0.24384)
			(end -0.67437 0.24384)
			(stroke
				(width 0.1)
				(type default)
			)
			(layer "F.Fab")
		)
		(fp_line
			(start 0.67437 2.04216)
			(end 0.67437 0.24384)
			(stroke
				(width 0.1)
				(type default)
			)
			(layer "F.Fab")
		)
		(pad "1" smd rect
			(at 0 0)
			(size 0.4064 1.016)
			(layers "F.Cu" "F.Mask" "F.Paste")
			(net "FAN_TACH0_CPU0_D1")
		)
		(pad "2" smd rect
			(at 0 2.286)
			(size 0.4064 1.016)
			(layers "F.Cu" "F.Mask" "F.Paste")
			(net "FAN_TACH0_CPU0_D2")
		)
	)
	(footprint ""
		(layer "F.Cu")
		(at 272.861532 -12.954 90)
		(property "Reference" "C5G7"
			(at 1.848866 0.752348 90)
			(unlocked yes)
			(layer "F.SilkS")
			(effects
				(font
					(size 1.27 0.9652)
					(thickness 0.1524)
				)
			)
		)
		(property "Value" ""
			(at 0 0 90)
			(layer "F.Fab")
			(effects
				(font
					(size 1.27 1.27)
				)
			)
		)
		(duplicate_pad_numbers_are_jumpers no)
		(fp_rect
			(start -0.500126 1.598422)
			(end 0.500126 -0.201422)
			(stroke
				(width 0)
				(type default)
			)
			(fill no)
			(layer "F.CrtYd")
		)
		(fp_line
			(start 0.500126 -0.201422)
			(end 0.500126 1.598422)
			(stroke
				(width 0.1)
				(type default)
			)
			(layer "F.Fab")
		)
		(fp_line
			(start -0.500126 -0.201422)
			(end 0.500126 -0.201422)
			(stroke
				(width 0.1)
				(type default)
			)
			(layer "F.Fab")
		)
		(fp_line
			(start 0.500126 1.598422)
			(end -0.500126 1.598422)
			(stroke
				(width 0.1)
				(type default)
			)
			(layer "F.Fab")
		)
		(fp_line
			(start -0.500126 1.598422)
			(end -0.500126 -0.201422)
			(stroke
				(width 0.1)
				(type default)
			)
			(layer "F.Fab")
		)
		(pad "1" smd rect
			(at 0 0)
			(size 0.889 0.9906)
			(layers "F.Cu" "F.Mask" "F.Paste")
			(net "PVDDQ_ABC")
		)
		(pad "2" smd rect
			(at 0 1.397)
			(size 0.889 0.9906)
			(layers "F.Cu" "F.Mask" "F.Paste")
			(net "GND")
		)
		(zone
			(layer "F.Cu")
			(hatch none 0.5)
			(connect_pads
				(clearance 0)
			)
			(min_thickness 0.25)
			(keepout
				(tracks allowed)
				(vias not_allowed)
				(pads allowed)
				(copperpour not_allowed)
				(footprints allowed)
			)
			(placement
				(enabled no)
				(sheetname "")
			)
			(fill
				(thermal_gap 0.5)
				(thermal_bridge_width 0.5)
				(island_removal_mode 0)
			)
			(polygon
				(pts
					(xy 273.814032 -12.4587) (xy 273.814032 -13.4493) (xy 273.306032 -13.4493) (xy 273.306032 -12.4587)
				)
			)
		)
		(zone
			(layer "F.Cu")
			(hatch none 0.5)
			(connect_pads
				(clearance 0)
			)
			(min_thickness 0.25)
			(keepout
				(tracks not_allowed)
				(vias allowed)
				(pads allowed)
				(copperpour not_allowed)
				(footprints allowed)
			)
			(placement
				(enabled no)
				(sheetname "")
			)
			(fill
				(thermal_gap 0.5)
				(thermal_bridge_width 0.5)
				(island_removal_mode 0)
			)
			(polygon
				(pts
					(xy 273.814032 -12.4587) (xy 273.814032 -13.4493) (xy 273.306032 -13.4493) (xy 273.306032 -12.4587)
				)
			)
		)
	)
	(footprint ""
		(layer "F.Cu")
		(at 281.776424 -80.9371)
		(property "Reference" "C6D1"
			(at 0 0 0)
			(layer "F.SilkS")
			(hide yes)
			(effects
				(font
					(size 1.27 1.27)
				)
			)
		)
		(property "Value" ""
			(at 0 0 0)
			(layer "F.Fab")
			(effects
				(font
					(size 1.27 1.27)
				)
			)
		)
		(duplicate_pad_numbers_are_jumpers no)
		(fp_poly
			(pts
				(xy -0.4953 -0.2032) (xy 0.4953 -0.2032) (xy 0.4953 1.6002) (xy -0.4953 1.6002)
			)
			(stroke
				(width 0)
				(type default)
			)
			(fill no)
			(layer "F.CrtYd")
		)
		(fp_line
			(start -0.4953 -0.2032)
			(end 0.4953 -0.2032)
			(stroke
				(width 0.1)
				(type default)
			)
			(layer "F.Fab")
		)
		(fp_line
			(start -0.4953 1.6002)
			(end -0.4953 -0.2032)
			(stroke
				(width 0.1)
				(type default)
			)
			(layer "F.Fab")
		)
		(fp_line
			(start 0.4953 -0.2032)
			(end 0.4953 1.6002)
			(stroke
				(width 0.1)
				(type default)
			)
			(layer "F.Fab")
		)
		(fp_line
			(start 0.4953 1.6002)
			(end -0.4953 1.6002)
			(stroke
				(width 0.1)
				(type default)
			)
			(layer "F.Fab")
		)
		(pad "1" smd rect
			(at 0 0)
			(size 0.762 0.889)
			(layers "F.Cu" "F.Mask" "F.Paste")
			(net "P1V8_MCP_CPU0")
		)
		(pad "2" smd rect
			(at 0 1.397)
			(size 0.762 0.889)
			(layers "F.Cu" "F.Mask" "F.Paste")
			(net "GND")
		)
		(zone
			(layer "F.Cu")
			(hatch none 0.5)
			(connect_pads
				(clearance 0)
			)
			(min_thickness 0.25)
			(keepout
				(tracks not_allowed)
				(vias allowed)
				(pads allowed)
				(copperpour not_allowed)
				(footprints allowed)
			)
			(placement
				(enabled no)
				(sheetname "")
			)
			(fill
				(thermal_gap 0.5)
				(thermal_bridge_width 0.5)
				(island_removal_mode 0)
			)
			(polygon
				(pts
					(xy 281.395424 -80.4926) (xy 282.157424 -80.4926) (xy 282.157424 -79.9846) (xy 281.395424 -79.9846)
				)
			)
		)
	)
	(footprint ""
		(layer "F.Cu")
		(at 405.47036 -57.79389)
		(property "Reference" "C8E9"
			(at 0 0 0)
			(layer "F.SilkS")
			(hide yes)
			(effects
				(font
					(size 1.27 1.27)
				)
			)
		)
		(property "Value" "*"
			(at -0.0762 -6.2357 0)
			(unlocked yes)
			(layer "F.Fab")
			(hide yes)
			(effects
				(font
					(size 1.27 1.016)
					(thickness 0.1524)
				)
			)
		)
		(property "Device Type" "SC22U16V5MX-4-GP_SMD-BCG5-SC22A"
			(at -0.0762 -8.2677 0)
			(unlocked yes)
			(layer "F.Fab")
			(hide yes)
			(effects
				(font
					(size 1.27 1.016)
					(thickness 0.1524)
				)
			)
		)
		(duplicate_pad_numbers_are_jumpers no)
		(fp_line
			(start 0.635 0)
			(end -0.635 0)
			(stroke
				(width 0.508)
				(type default)
			)
			(layer "F.SilkS")
		)
		(fp_rect
			(start -0.9652 1.778)
			(end 0.9652 -1.778)
			(stroke
				(width 0)
				(type default)
			)
			(fill no)
			(layer "F.CrtYd")
		)
		(fp_poly
			(pts
				(xy -0.9652 -1.778) (xy 0.9652 -1.778) (xy 0.9652 1.778) (xy -0.9652 1.778)
			)
			(stroke
				(width 0)
				(type default)
			)
			(fill no)
			(layer "F.Fab")
		)
		(pad "1" smd rect
			(at 0 -0.9652)
			(size 1.397 1.143)
			(layers "F.Cu" "F.Mask" "F.Paste")
			(net "P5V_STBY")
		)
		(pad "2" smd rect
			(at 0 0.9652)
			(size 1.397 1.143)
			(layers "F.Cu" "F.Mask" "F.Paste")
			(net "GND")
		)
	)
	(footprint ""
		(layer "F.Cu")
		(at 357.0605 -146.61642)
		(property "Reference" "C7W2"
			(at 0 0 0)
			(layer "F.SilkS")
			(hide yes)
			(effects
				(font
					(size 1.27 1.27)
				)
			)
		)
		(property "Value" "*"
			(at 3.5941 -1.41605 0)
			(unlocked yes)
			(layer "F.Fab")
			(hide yes)
			(effects
				(font
					(size 0.889 0.889)
					(thickness 0.1524)
				)
			)
		)
		(property "Device Type" "SE100U16VM-48-GP_SMD-TCG2-SE10A"
			(at 3.5941 -2.94005 0)
			(unlocked yes)
			(layer "F.Fab")
			(hide yes)
			(effects
				(font
					(size 0.889 0.889)
					(thickness 0.1524)
				)
			)
		)
		(duplicate_pad_numbers_are_jumpers no)
		(fp_line
			(start -2.7559 -2.0955)
			(end -2.0955 -2.7559)
			(stroke
				(width 0.1524)
				(type default)
			)
			(layer "F.SilkS")
		)
		(fp_line
			(start -2.7559 2.7559)
			(end -2.7559 -2.0955)
			(stroke
				(width 0.1524)
				(type default)
			)
			(layer "F.SilkS")
		)
		(fp_line
			(start -2.0955 -2.7559)
			(end -1.0287 -2.7559)
			(stroke
				(width 0.1524)
				(type default)
			)
			(layer "F.SilkS")
		)
		(fp_line
			(start -1.0287 2.7559)
			(end -2.7559 2.7559)
			(stroke
				(width 0.1524)
				(type default)
			)
			(layer "F.SilkS")
		)
		(fp_line
			(start 1.0287 -2.7559)
			(end 2.0955 -2.7559)
			(stroke
				(width 0.1524)
				(type default)
			)
			(layer "F.SilkS")
		)
		(fp_line
			(start 2.0955 -2.7559)
			(end 2.7559 -2.0955)
			(stroke
				(width 0.1524)
				(type default)
			)
			(layer "F.SilkS")
		)
		(fp_line
			(start 2.7559 -2.0955)
			(end 2.7559 2.7559)
			(stroke
				(width 0.1524)
				(type default)
			)
			(layer "F.SilkS")
		)
		(fp_line
			(start 2.7559 2.7559)
			(end 1.0287 2.7559)
			(stroke
				(width 0.1524)
				(type default)
			)
			(layer "F.SilkS")
		)
		(fp_poly
			(pts
				(xy -0.8001 3.7084) (xy -0.8001 2.7559) (xy -2.7559 2.7559) (xy -2.7559 -2.7559) (xy -0.8001 -2.7559)
				(xy -0.8001 -3.7084) (xy 0.8001 -3.7084) (xy 0.8001 -2.7559) (xy 2.7559 -2.7559) (xy 2.7559 2.7559)
				(xy 0.8001 2.7559) (xy 0.8001 3.7084)
			)
			(stroke
				(width 0)
				(type default)
			)
			(fill no)
			(layer "F.CrtYd")
		)
		(fp_poly
			(pts
				(xy -0.8001 3.7084) (xy -0.8001 2.7559) (xy -2.7559 2.7559) (xy -2.7559 -2.7559) (xy -0.8001 -2.7559)
				(xy -0.8001 -3.7084) (xy 0.8001 -3.7084) (xy 0.8001 -2.7559) (xy 2.7559 -2.7559) (xy 2.7559 2.7559)
				(xy 0.8001 2.7559) (xy 0.8001 3.7084)
			)
			(stroke
				(width 0)
				(type default)
			)
			(fill no)
			(layer "F.Fab")
		)
		(pad "1" smd rect
			(at 0 -2.199894)
			(size 1.6002 2.9972)
			(layers "F.Cu" "F.Mask" "F.Paste")
			(net "VR_FET_SW_P12V_STBY_PVDDQ_DEF")
		)
		(pad "2" smd rect
			(at 0 2.199894)
			(size 1.6002 2.9972)
			(layers "F.Cu" "F.Mask" "F.Paste")
			(net "GND")
		)
	)
	(footprint ""
		(layer "F.Cu")
		(at 181.847998 -4.432808 180)
		(property "Reference" "C4G14"
			(at 0 0 180)
			(layer "F.SilkS")
			(hide yes)
			(effects
				(font
					(size 1.27 1.27)
				)
			)
		)
		(property "Value" ""
			(at 0 0 180)
			(layer "F.Fab")
			(effects
				(font
					(size 1.27 1.27)
				)
			)
		)
		(duplicate_pad_numbers_are_jumpers no)
		(fp_rect
			(start 0.3048 0.9906)
			(end -0.3048 -0.1016)
			(stroke
				(width 0)
				(type default)
			)
			(fill no)
			(layer "F.CrtYd")
		)
		(fp_line
			(start 0.3048 0.9906)
			(end 0.3048 -0.1016)
			(stroke
				(width 0.1)
				(type default)
			)
			(layer "F.Fab")
		)
		(fp_line
			(start 0.3048 -0.1016)
			(end -0.3048 -0.1016)
			(stroke
				(width 0.1)
				(type default)
			)
			(layer "F.Fab")
		)
		(fp_line
			(start -0.3048 0.9906)
			(end 0.3048 0.9906)
			(stroke
				(width 0.1)
				(type default)
			)
			(layer "F.Fab")
		)
		(fp_line
			(start -0.3048 -0.1016)
			(end -0.3048 0.9906)
			(stroke
				(width 0.1)
				(type default)
			)
			(layer "F.Fab")
		)
		(pad "1" smd rect
			(at 0 0 180)
			(size 0.508 0.508)
			(layers "F.Cu" "F.Mask" "F.Paste")
			(net "PWRGD_PVTT_ABC_CPU0_R")
		)
		(pad "2" smd rect
			(at 0 0.889 180)
			(size 0.508 0.508)
			(layers "F.Cu" "F.Mask" "F.Paste")
			(net "GND")
		)
		(zone
			(layer "F.Cu")
			(hatch none 0.5)
			(connect_pads
				(clearance 0)
			)
			(min_thickness 0.25)
			(keepout
				(tracks allowed)
				(vias not_allowed)
				(pads allowed)
				(copperpour not_allowed)
				(footprints allowed)
			)
			(placement
				(enabled no)
				(sheetname "")
			)
			(fill
				(thermal_gap 0.5)
				(thermal_bridge_width 0.5)
				(island_removal_mode 0)
			)
			(polygon
				(pts
					(xy 181.593998 -5.067808) (xy 181.593998 -4.686808) (xy 182.101998 -4.686808) (xy 182.101998 -5.067808)
				)
			)
		)
		(zone
			(layer "F.Cu")
			(hatch none 0.5)
			(connect_pads
				(clearance 0)
			)
			(min_thickness 0.25)
			(keepout
				(tracks not_allowed)
				(vias allowed)
				(pads allowed)
				(copperpour not_allowed)
				(footprints allowed)
			)
			(placement
				(enabled no)
				(sheetname "")
			)
			(fill
				(thermal_gap 0.5)
				(thermal_bridge_width 0.5)
				(island_removal_mode 0)
			)
			(polygon
				(pts
					(xy 181.593998 -5.067808) (xy 181.593998 -4.686808) (xy 182.101998 -4.686808) (xy 182.101998 -5.067808)
				)
			)
		)
	)
	(footprint ""
		(layer "F.Cu")
		(at 459.3844 -15.3924)
		(property "Reference" "C8F14"
			(at 0 0 0)
			(layer "F.SilkS")
			(hide yes)
			(effects
				(font
					(size 1.27 1.27)
				)
			)
		)
		(property "Value" "*"
			(at 0 -9.7155 0)
			(unlocked yes)
			(layer "F.Fab")
			(hide yes)
			(effects
				(font
					(size 1.27 1.016)
					(thickness 0.1524)
				)
			)
		)
		(property "Device Type" "ST470U6D3VDM-7-GP_SMD-TCG4-ST4A"
			(at 0 -11.2395 0)
			(unlocked yes)
			(layer "F.Fab")
			(hide yes)
			(effects
				(font
					(size 1.27 1.016)
					(thickness 0.1524)
				)
			)
		)
		(duplicate_pad_numbers_are_jumpers no)
		(fp_line
			(start -2.286 -4.8768)
			(end -2.286 -2.032)
			(stroke
				(width 0.1524)
				(type default)
			)
			(layer "F.SilkS")
		)
		(fp_line
			(start -2.286 4.8768)
			(end -2.286 2.032)
			(stroke
				(width 0.1524)
				(type default)
			)
			(layer "F.SilkS")
		)
		(fp_line
			(start 2.1082 -4.699)
			(end -2.1082 -4.699)
			(stroke
				(width 0.508)
				(type default)
			)
			(layer "F.SilkS")
		)
		(fp_line
			(start 2.286 -4.8768)
			(end -2.286 -4.8768)
			(stroke
				(width 0.1524)
				(type default)
			)
			(layer "F.SilkS")
		)
		(fp_line
			(start 2.286 -2.032)
			(end 2.286 -4.8768)
			(stroke
				(width 0.1524)
				(type default)
			)
			(layer "F.SilkS")
		)
		(fp_line
			(start 2.286 2.032)
			(end 2.286 4.8768)
			(stroke
				(width 0.1524)
				(type default)
			)
			(layer "F.SilkS")
		)
		(fp_line
			(start 2.286 4.8768)
			(end -2.286 4.8768)
			(stroke
				(width 0.1524)
				(type default)
			)
			(layer "F.SilkS")
		)
		(fp_rect
			(start -2.1463 3.6449)
			(end 2.1463 -3.6449)
			(stroke
				(width 0)
				(type default)
			)
			(fill no)
			(layer "F.CrtYd")
		)
		(fp_poly
			(pts
				(xy -2.54 4.953) (xy -2.54 4.2926) (xy -3.81 4.2926) (xy -3.81 -4.2926) (xy -2.54 -4.2926) (xy -2.54 -4.953)
				(xy 2.54 -4.953) (xy 2.54 -4.2926) (xy 3.81 -4.2926) (xy 3.81 -1.6256) (xy 2.1463 -1.6256) (xy 2.1463 -3.6449)
				(xy -2.1463 -3.6449) (xy -2.1463 3.6449) (xy 2.1463 3.6449) (xy 2.1463 -1.6129) (xy 3.81 -1.6129)
				(xy 3.81 4.2926) (xy 2.54 4.2926) (xy 2.54 4.953)
			)
			(stroke
				(width 0)
				(type default)
			)
			(fill no)
			(layer "F.CrtYd")
		)
		(fp_rect
			(start -3.81 4.2926)
			(end -2.54 -4.2926)
			(stroke
				(width 0)
				(type default)
			)
			(fill no)
			(layer "F.Fab")
		)
		(fp_rect
			(start -2.54 4.953)
			(end 2.54 -4.953)
			(stroke
				(width 0)
				(type default)
			)
			(fill no)
			(layer "F.Fab")
		)
		(fp_rect
			(start 2.54 4.2926)
			(end 3.81 -4.2926)
			(stroke
				(width 0)
				(type default)
			)
			(fill no)
			(layer "F.Fab")
		)
		(pad "1" smd rect
			(at 0 -3.1496)
			(size 2.413 2.286)
			(layers "F.Cu" "F.Mask" "F.Paste")
			(net "P3V3_STBY")
		)
		(pad "2" smd rect
			(at 0 3.1496)
			(size 2.413 2.286)
			(layers "F.Cu" "F.Mask" "F.Paste")
			(net "GND")
		)
		(zone
			(layer "F.Cu")
			(hatch none 0.5)
			(connect_pads
				(clearance 0)
			)
			(min_thickness 0.25)
			(keepout
				(tracks allowed)
				(vias not_allowed)
				(pads allowed)
				(copperpour not_allowed)
				(footprints allowed)
			)
			(placement
				(enabled no)
				(sheetname "")
			)
			(fill
				(thermal_gap 0.5)
				(thermal_bridge_width 0.5)
				(island_removal_mode 0)
			)
			(polygon
				(pts
					(xy 457.8731 -10.795) (xy 460.8957 -10.795) (xy 460.8957 -13.6906) (xy 460.8957 -14.0208) (xy 457.8731 -14.0208)
					(xy 457.8731 -13.6906)
				)
			)
		)
		(zone
			(layer "F.Cu")
			(hatch none 0.5)
			(connect_pads
				(clearance 0)
			)
			(min_thickness 0.25)
			(keepout
				(tracks allowed)
				(vias not_allowed)
				(pads allowed)
				(copperpour not_allowed)
				(footprints allowed)
			)
			(placement
				(enabled no)
				(sheetname "")
			)
			(fill
				(thermal_gap 0.5)
				(thermal_bridge_width 0.5)
				(island_removal_mode 0)
			)
			(polygon
				(pts
					(xy 460.8957 -17.0815) (xy 460.8957 -19.9898) (xy 457.8731 -19.9898) (xy 457.8731 -17.0942) (xy 457.8731 -16.764)
					(xy 460.8957 -16.764)
				)
			)
		)
	)
)
